# S9S_MB_2U (Grand Teton) — schematic netlist excerpt (pin names and nets, part order shuffled) for the footprints in the layout excerpt that follows; sources: Cadence DE-HDL packaged netlist, KiCad conversion of 03242023_DA0F0TMBIJ0_F0T_Motherboard_J_brd_V01_OCP.brd

R2911  Q_RES  4.7K 5% EMPTY  pkg 0402LF  page 151 : A = P3V3_AUX ; B = RST_SWB_BIC_BUF_R_N
R3611  Q_RES  4.7K 1% CHIP  pkg 0402LF  page 172 : A = GND ; B = INA230_4_A0

(kicad_pcb
	(version 20260206)
	(generator "pcbnew")
	(generator_version "10.0")
	(general
		(thickness 1.6)
		(legacy_teardrops no)
	)
	(paper "A4")
	(title_block
		(title "03242023_DA0F0TMBIJ0_F0T_Motherboard_J_brd_V01_OCP.brd")
		(comment 1 "Grand Teton / footprints 1140-1141 of 6105")
	)
	(layers
		(0 "F.Cu" signal "TOP")
		(4 "In1.Cu" signal "GND")
		(6 "In2.Cu" signal "IN1")
		(8 "In3.Cu" signal "GND1")
		(10 "In4.Cu" signal "IN2")
		(12 "In5.Cu" signal "GND2")
		(14 "In6.Cu" signal "IN3")
		(16 "In7.Cu" signal "GND3")
		(18 "In8.Cu" signal "VCC")
		(20 "In9.Cu" signal "VCC1")
		(22 "In10.Cu" signal "GND4")
		(24 "In11.Cu" signal "IN4")
		(26 "In12.Cu" signal "GND5")
		(28 "In13.Cu" signal "IN5")
		(30 "In14.Cu" signal "GND6")
		(32 "In15.Cu" signal "IN6")
		(34 "In16.Cu" signal "GND7")
		(2 "B.Cu" signal "BOTTOM")
		(9 "F.Adhes" user "F.Adhesive")
		(11 "B.Adhes" user "B.Adhesive")
		(13 "F.Paste" user "Package Geometry/Pastemask Top")
		(15 "B.Paste" user "Package Geometry/Pastemask Bottom")
		(5 "F.SilkS" user "Ref Des/Silkscreen Top")
		(7 "B.SilkS" user "Ref Des/Silkscreen Bottom")
		(1 "F.Mask" user "Board Geometry/Soldermask Top")
		(3 "B.Mask" user "Board Geometry/Soldermask Bottom")
		(17 "Dwgs.User" user "User.Drawings")
		(19 "Cmts.User" user "User.Comments")
		(21 "Eco1.User" user "User.Eco1")
		(23 "Eco2.User" user "User.Eco2")
		(25 "Edge.Cuts" user "Board Geometry/Outline")
		(27 "Margin" user)
		(31 "F.CrtYd" user "Package Geometry/Place Bound Top")
		(29 "B.CrtYd" user "Package Geometry/Place Bound Bottom")
		(35 "F.Fab" user "Ref Des/Assembly Top")
		(33 "B.Fab" user "Ref Des/Assembly Bottom")
	)
	(footprint ""
		(layer "F.Cu")
		(at 148.197824 -51.404012)
		(property "Reference" "R3611"
			(at 0 0 0)
			(layer "F.SilkS")
			(hide yes)
			(effects
				(font
					(size 1.27 1.27)
				)
			)
		)
		(property "Value" ""
			(at 0 0 0)
			(layer "F.Fab")
			(effects
				(font
					(size 1.27 1.27)
				)
			)
		)
		(duplicate_pad_numbers_are_jumpers no)
		(fp_line
			(start -0.7874 -0.4064)
			(end 0.7874 -0.4064)
			(stroke
				(width 0.1524)
				(type default)
			)
			(layer "F.SilkS")
		)
		(fp_line
			(start -0.7874 0.4064)
			(end -0.7874 -0.4064)
			(stroke
				(width 0.1524)
				(type default)
			)
			(layer "F.SilkS")
		)
		(fp_line
			(start 0.7874 -0.4064)
			(end 0.7874 0.4064)
			(stroke
				(width 0.1524)
				(type default)
			)
			(layer "F.SilkS")
		)
		(fp_line
			(start 0.7874 0.4064)
			(end -0.7874 0.4064)
			(stroke
				(width 0.1524)
				(type default)
			)
			(layer "F.SilkS")
		)
		(fp_line
			(start -0.67945 -0.305054)
			(end -0.12065 -0.305054)
			(stroke
				(width 0.1)
				(type default)
			)
			(layer "F.Fab")
		)
		(fp_line
			(start -0.67945 0.3048)
			(end -0.67945 -0.305054)
			(stroke
				(width 0.1)
				(type default)
			)
			(layer "F.Fab")
		)
		(fp_line
			(start -0.12065 -0.305054)
			(end -0.12065 -0.2794)
			(stroke
				(width 0.1)
				(type default)
			)
			(layer "F.Fab")
		)
		(fp_line
			(start -0.12065 -0.2794)
			(end 0.12065 -0.2794)
			(stroke
				(width 0.1)
				(type default)
			)
			(layer "F.Fab")
		)
		(fp_line
			(start -0.12065 0.2794)
			(end -0.12065 0.3048)
			(stroke
				(width 0.1)
				(type default)
			)
			(layer "F.Fab")
		)
		(fp_line
			(start -0.12065 0.3048)
			(end -0.67945 0.3048)
			(stroke
				(width 0.1)
				(type default)
			)
			(layer "F.Fab")
		)
		(fp_line
			(start 0.120396 0.2794)
			(end -0.12065 0.2794)
			(stroke
				(width 0.1)
				(type default)
			)
			(layer "F.Fab")
		)
		(fp_line
			(start 0.120396 0.3048)
			(end 0.120396 0.2794)
			(stroke
				(width 0.1)
				(type default)
			)
			(layer "F.Fab")
		)
		(fp_line
			(start 0.12065 -0.3048)
			(end 0.67945 -0.3048)
			(stroke
				(width 0.1)
				(type default)
			)
			(layer "F.Fab")
		)
		(fp_line
			(start 0.12065 -0.2794)
			(end 0.12065 -0.3048)
			(stroke
				(width 0.1)
				(type default)
			)
			(layer "F.Fab")
		)
		(fp_line
			(start 0.67945 -0.3048)
			(end 0.67945 0.3048)
			(stroke
				(width 0.1)
				(type default)
			)
			(layer "F.Fab")
		)
		(fp_line
			(start 0.67945 0.3048)
			(end 0.120396 0.3048)
			(stroke
				(width 0.1)
				(type default)
			)
			(layer "F.Fab")
		)
		(pad "1" smd circle
			(at -0.40005 0)
			(size 0 0)
			(layers "F.Cu" "F.Mask" "F.Paste")
			(net "GND")
		)
		(pad "2" smd circle
			(at 0.40005 0)
			(size 0 0)
			(layers "F.Cu" "F.Mask" "F.Paste")
			(net "INA230_4_A0")
		)
	)
	(footprint ""
		(layer "F.Cu")
		(at 176.17948 -422.366948 180)
		(property "Reference" "R2911"
			(at 0 0 180)
			(layer "F.SilkS")
			(hide yes)
			(effects
				(font
					(size 1.27 1.27)
				)
			)
		)
		(property "Value" ""
			(at 0 0 180)
			(layer "F.Fab")
			(effects
				(font
					(size 1.27 1.27)
				)
			)
		)
		(duplicate_pad_numbers_are_jumpers no)
		(fp_line
			(start 0.7874 0.4064)
			(end -0.7874 0.4064)
			(stroke
				(width 0.1524)
				(type default)
			)
			(layer "F.SilkS")
		)
		(fp_line
			(start 0.7874 -0.4064)
			(end 0.7874 0.4064)
			(stroke
				(width 0.1524)
				(type default)
			)
			(layer "F.SilkS")
		)
		(fp_line
			(start -0.7874 0.4064)
			(end -0.7874 -0.4064)
			(stroke
				(width 0.1524)
				(type default)
			)
			(layer "F.SilkS")
		)
		(fp_line
			(start -0.7874 -0.4064)
			(end 0.7874 -0.4064)
			(stroke
				(width 0.1524)
				(type default)
			)
			(layer "F.SilkS")
		)
		(fp_line
			(start 0.67945 0.3048)
			(end 0.120396 0.3048)
			(stroke
				(width 0.1)
				(type default)
			)
			(layer "F.Fab")
		)
		(fp_line
			(start 0.67945 -0.3048)
			(end 0.67945 0.3048)
			(stroke
				(width 0.1)
				(type default)
			)
			(layer "F.Fab")
		)
		(fp_line
			(start 0.12065 -0.2794)
			(end 0.12065 -0.3048)
			(stroke
				(width 0.1)
				(type default)
			)
			(layer "F.Fab")
		)
		(fp_line
			(start 0.12065 -0.3048)
			(end 0.67945 -0.3048)
			(stroke
				(width 0.1)
				(type default)
			)
			(layer "F.Fab")
		)
		(fp_line
			(start 0.120396 0.3048)
			(end 0.120396 0.2794)
			(stroke
				(width 0.1)
				(type default)
			)
			(layer "F.Fab")
		)
		(fp_line
			(start 0.120396 0.2794)
			(end -0.12065 0.2794)
			(stroke
				(width 0.1)
				(type default)
			)
			(layer "F.Fab")
		)
		(fp_line
			(start -0.12065 0.3048)
			(end -0.67945 0.3048)
			(stroke
				(width 0.1)
				(type default)
			)
			(layer "F.Fab")
		)
		(fp_line
			(start -0.12065 0.2794)
			(end -0.12065 0.3048)
			(stroke
				(width 0.1)
				(type default)
			)
			(layer "F.Fab")
		)
		(fp_line
			(start -0.12065 -0.2794)
			(end 0.12065 -0.2794)
			(stroke
				(width 0.1)
				(type default)
			)
			(layer "F.Fab")
		)
		(fp_line
			(start -0.12065 -0.305054)
			(end -0.12065 -0.2794)
			(stroke
				(width 0.1)
				(type default)
			)
			(layer "F.Fab")
		)
		(fp_line
			(start -0.67945 0.3048)
			(end -0.67945 -0.305054)
			(stroke
				(width 0.1)
				(type default)
			)
			(layer "F.Fab")
		)
		(fp_line
			(start -0.67945 -0.305054)
			(end -0.12065 -0.305054)
			(stroke
				(width 0.1)
				(type default)
			)
			(layer "F.Fab")
		)
		(pad "1" smd circle
			(at -0.40005 0 180)
			(size 0 0)
			(layers "F.Cu" "F.Mask" "F.Paste")
			(net "P3V3_AUX")
		)
		(pad "2" smd circle
			(at 0.40005 0 180)
			(size 0 0)
			(layers "F.Cu" "F.Mask" "F.Paste")
			(net "RST_SWB_BIC_BUF_R_N")
		)
	)
)
